(kicad_pcb
	(version 20221018)
	(generator pcbnew)
	(general
    (thickness 1.656)
  )
	(paper "A4")
	(title_block
    (title "SDI-MIPI Bridge")
    (date "2023-08-09")
    (rev "1.3.4")
    (company "Antmicro")
		(comment 9 "footprints 39-48 of 190")
	)
	(layers
    (0 "F.Cu" signal)
    (1 "In1.Cu" power)
    (2 "In2.Cu" power)
    (3 "In3.Cu" signal)
    (4 "In4.Cu" signal)
    (31 "B.Cu" signal)
    (32 "B.Adhes" user "B.Adhesive")
    (33 "F.Adhes" user "F.Adhesive")
    (34 "B.Paste" user)
    (35 "F.Paste" user)
    (36 "B.SilkS" user "B.Silkscreen")
    (37 "F.SilkS" user "F.Silkscreen")
    (38 "B.Mask" user)
    (39 "F.Mask" user)
    (40 "Dwgs.User" user "User.Drawings")
    (41 "Cmts.User" user "User.Comments")
    (42 "Eco1.User" user "User.Eco1")
    (43 "Eco2.User" user "User.Eco2")
    (44 "Edge.Cuts" user)
    (45 "Margin" user)
    (46 "B.CrtYd" user "B.Courtyard")
    (47 "F.CrtYd" user "F.Courtyard")
    (48 "B.Fab" user)
    (49 "F.Fab" user)
  )
	(footprint "sdi-mipi-bridge-footprints:R_0603_1608Metric" (layer "F.Cu")
    (at 108.35 122.9 -90)
    (descr "Resistor SMD 0603")
    (tags "resistor SMD 0603")
    (property "Author" "Antmicro")
    (property "License" "Apache-2.0")
    (property "MPN" "CR0603-FX-75R0ELF")
    (property "Manufacturer" "Bourns")
    (property "Sheetfile" "sdi-mipi-bridge.kicad_sch")
    (property "Sheetname" "")
    (property "Tolerance" "1%")
    (property "Val" "75R")
    (property "ki_description" "75R resistor in 0603 package with 1% tolerance")
    (attr smd)
    (fp_text reference "R18" (at 8 -1.45 90) (layer "F.SilkS")
        (effects (font (size 0.65 0.65) (thickness 0.15)) (justify right bottom))
    )
    (fp_text value "R_75R_0603" (at 0 1.6 90) (layer "F.Fab") hide
        (effects (font (size 0.7 0.7) (thickness 0.15)) (justify right bottom))
    )
    (fp_text user "${REFERENCE}" (at -1.25 3.898 90) (layer "F.Fab") hide
        (effects (font (size 0.7 0.7) (thickness 0.15)) (justify right bottom))
    )
    (fp_text user "Author: Antmicro" (at -1.25 4.9 90) (layer "F.Fab") hide
        (effects (font (size 0.7 0.7) (thickness 0.15)) (justify right bottom))
    )
    (fp_text user "License: Apache-2.0" (at -1.25 5.9 90) (layer "F.Fab") hide
        (effects (font (size 0.7 0.7) (thickness 0.15)) (justify right bottom))
    )
    (fp_line (start -0.3 -0.3) (end 0.3 -0.3)
      (stroke (width 0.15) (type solid)) (layer "F.SilkS"))
    (fp_line (start -0.3 0.3) (end 0.3 0.3)
      (stroke (width 0.15) (type solid)) (layer "F.SilkS"))
    (fp_rect (start -1.25 -0.7) (end 1.25 0.7)
      (stroke (width 0.05) (type solid)) (fill none) (layer "F.CrtYd"))
    (fp_rect (start -0.8 -0.4) (end 0.8 0.4)
      (stroke (width 0.15) (type solid)) (fill none) (layer "F.Fab"))
    (pad "1" smd roundrect (at -0.7 0 270) (size 0.6 0.8) (layers "F.Cu" "F.Paste" "F.Mask") (roundrect_rratio 0.2)
      (net 27 "Net-(U3-SDO+)") (pintype "passive"))
    (pad "2" smd roundrect (at 0.7 0 270) (size 0.6 0.8) (layers "F.Cu" "F.Paste" "F.Mask") (roundrect_rratio 0.2)
      (net 57 "VDD") (pintype "passive"))
  )
	(footprint "sdi-mipi-bridge-footprints:C_0402_1005Metric" (layer "F.Cu")
    (at 107.9 118.18 180)
    (descr "Capacitor SMD 0402")
    (tags "capacitor SMD 0402")
    (property "Author" "Antmicro")
    (property "Dielectric" "X7R")
    (property "License" "Apache-2.0")
    (property "MPN" "GRM155R71H103KA88D")
    (property "Manufacturer" "Murata")
    (property "Sheetfile" "sdi-mipi-bridge.kicad_sch")
    (property "Sheetname" "")
    (property "Val" "10n")
    (property "Voltage" "50V")
    (property "ki_description" " ")
    (attr smd)
    (fp_text reference "C36" (at -1 0.48) (layer "F.SilkS")
        (effects (font (size 0.65 0.65) (thickness 0.15)) (justify right bottom))
    )
    (fp_text value "C_10n_0402" (at 0 1.4) (layer "F.Fab") hide
        (effects (font (size 0.7 0.7) (thickness 0.15)) (justify right bottom))
    )
    (fp_text user "${REFERENCE}" (at -0.932 3.168) (layer "F.Fab") hide
        (effects (font (size 0.7 0.7) (thickness 0.15)) (justify right bottom))
    )
    (fp_text user "License: Apache-2.0" (at -0.932 5.17) (layer "F.Fab") hide
        (effects (font (size 0.7 0.7) (thickness 0.15)) (justify right bottom))
    )
    (fp_text user "Author: Antmicro" (at -0.932 4.17) (layer "F.Fab") hide
        (effects (font (size 0.7 0.7) (thickness 0.15)) (justify right bottom))
    )
    (fp_rect (start -0.94 -0.47) (end 0.94 0.47)
      (stroke (width 0.05) (type solid)) (fill none) (layer "F.CrtYd"))
    (fp_rect (start -0.499 -0.249) (end 0.499 0.249)
      (stroke (width 0.15) (type solid)) (fill none) (layer "F.Fab"))
    (pad "1" smd roundrect (at -0.484 0 180) (size 0.59 0.64) (layers "F.Cu" "F.Paste" "F.Mask") (roundrect_rratio 0.25)
      (net 57 "VDD") (pintype "passive"))
    (pad "2" smd roundrect (at 0.484 0 180) (size 0.59 0.64) (layers "F.Cu" "F.Paste" "F.Mask") (roundrect_rratio 0.25)
      (net 3 "GNDA") (pintype "passive"))
  )
	(footprint "sdi-mipi-bridge-footprints:C_0402_1005Metric" (layer "F.Cu")
    (at 105.55 122.8 -90)
    (descr "Capacitor SMD 0402")
    (tags "capacitor SMD 0402")
    (property "Author" "Antmicro")
    (property "Dielectric" "")
    (property "License" "Apache-2.0")
    (property "MPN" "GRM155R61A475MEAAD")
    (property "Manufacturer" "Murata")
    (property "Sheetfile" "sdi-mipi-bridge.kicad_sch")
    (property "Sheetname" "")
    (property "Val" "4u7")
    (property "Voltage" "")
    (property "ki_description" " ")
    (attr smd)
    (fp_text reference "C31" (at 8.1 -1.65 90) (layer "F.SilkS")
        (effects (font (size 0.65 0.65) (thickness 0.15)) (justify right bottom))
    )
    (fp_text value "C_4u7_0402" (at 0 1.4 90) (layer "F.Fab") hide
        (effects (font (size 0.7 0.7) (thickness 0.15)) (justify right bottom))
    )
    (fp_text user "License: Apache-2.0" (at -0.932 5.17 90) (layer "F.Fab") hide
        (effects (font (size 0.7 0.7) (thickness 0.15)) (justify right bottom))
    )
    (fp_text user "Author: Antmicro" (at -0.932 4.17 90) (layer "F.Fab") hide
        (effects (font (size 0.7 0.7) (thickness 0.15)) (justify right bottom))
    )
    (fp_text user "${REFERENCE}" (at -0.932 3.168 90) (layer "F.Fab") hide
        (effects (font (size 0.7 0.7) (thickness 0.15)) (justify right bottom))
    )
    (fp_rect (start -0.94 -0.47) (end 0.94 0.47)
      (stroke (width 0.05) (type solid)) (fill none) (layer "F.CrtYd"))
    (fp_rect (start -0.499 -0.249) (end 0.499 0.249)
      (stroke (width 0.15) (type solid)) (fill none) (layer "F.Fab"))
    (pad "1" smd roundrect (at -0.484 0 270) (size 0.59 0.64) (layers "F.Cu" "F.Paste" "F.Mask") (roundrect_rratio 0.25)
      (net 68 "Net-(C27-Pad2)") (pintype "passive"))
    (pad "2" smd roundrect (at 0.484 0 270) (size 0.59 0.64) (layers "F.Cu" "F.Paste" "F.Mask") (roundrect_rratio 0.25)
      (net 140 "Net-(C31-Pad2)") (pintype "passive"))
  )
	(footprint "sdi-mipi-bridge-footprints:R_0402_1005Metric" (layer "F.Cu")
    (at 114.3 124.282 180)
    (descr "Resistor SMD 0402")
    (tags "resistor SMD 0402")
    (property "Author" "Antmicro")
    (property "Current" "1A")
    (property "License" "Apache-2.0")
    (property "MPN" "ERJ2GE0R00X")
    (property "Manufacturer" "Panasonic")
    (property "Sheetfile" "sdi-mipi-bridge.kicad_sch")
    (property "Sheetname" "")
    (property "Tolerance" "")
    (property "Val" "0R")
    (property "ki_description" "0R resistor in 0402 package with unspecified tolerance")
    (attr smd)
    (fp_text reference "R71" (at 1 -2.318 180) (layer "F.SilkS")
        (effects (font (size 0.65 0.65) (thickness 0.15)) (justify left bottom))
    )
    (fp_text value "R_0R_0402" (at 0 1.4 180) (layer "F.Fab") hide
        (effects (font (size 0.7 0.7) (thickness 0.15)) (justify left bottom))
    )
    (fp_text user "Author: Antmicro" (at -0.95 4.169 180) (layer "F.Fab") hide
        (effects (font (size 0.7 0.7) (thickness 0.15)) (justify left bottom))
    )
    (fp_text user "${REFERENCE}" (at -0.95 3.168 180) (layer "F.Fab") hide
        (effects (font (size 0.7 0.7) (thickness 0.15)) (justify left bottom))
    )
    (fp_text user "License: Apache-2.0" (at -0.95 5.169 180) (layer "F.Fab") hide
        (effects (font (size 0.7 0.7) (thickness 0.15)) (justify left bottom))
    )
    (fp_rect (start -0.93 -0.47) (end 0.93 0.47)
      (stroke (width 0.05) (type solid)) (fill none) (layer "F.CrtYd"))
    (fp_rect (start -0.5 -0.25) (end 0.5 0.25)
      (stroke (width 0.15) (type solid)) (fill none) (layer "F.Fab"))
    (pad "1" smd roundrect (at -0.485 0 180) (size 0.59 0.64) (layers "F.Cu" "F.Paste" "F.Mask") (roundrect_rratio 0.25)
      (net 57 "VDD") (pintype "passive"))
    (pad "2" smd roundrect (at 0.485 0 180) (size 0.59 0.64) (layers "F.Cu" "F.Paste" "F.Mask") (roundrect_rratio 0.25)
      (net 73 "Net-(U3-~{EQ_EN})") (pintype "passive"))
  )
	(footprint "sdi-mipi-bridge-footprints:C_0402_1005Metric" (layer "F.Cu")
    (at 106.25 119.52 180)
    (descr "Capacitor SMD 0402")
    (tags "capacitor SMD 0402")
    (property "Author" "Antmicro")
    (property "Dielectric" "")
    (property "License" "Apache-2.0")
    (property "MPN" "MC0402B562K160CT")
    (property "Manufacturer" "Multicomp")
    (property "Sheetfile" "sdi-mipi-bridge.kicad_sch")
    (property "Sheetname" "")
    (property "Val" "5n6")
    (property "Voltage" "")
    (property "ki_description" " ")
    (attr smd)
    (fp_text reference "C27" (at -2.15 -9.58) (layer "F.SilkS")
        (effects (font (size 0.65 0.65) (thickness 0.15)) (justify right bottom))
    )
    (fp_text value "C_5n6_0402" (at 0 1.4) (layer "F.Fab") hide
        (effects (font (size 0.7 0.7) (thickness 0.15)) (justify right bottom))
    )
    (fp_text user "Author: Antmicro" (at -0.932 4.17) (layer "F.Fab") hide
        (effects (font (size 0.7 0.7) (thickness 0.15)) (justify right bottom))
    )
    (fp_text user "License: Apache-2.0" (at -0.932 5.17) (layer "F.Fab") hide
        (effects (font (size 0.7 0.7) (thickness 0.15)) (justify right bottom))
    )
    (fp_text user "${REFERENCE}" (at -0.932 3.168) (layer "F.Fab") hide
        (effects (font (size 0.7 0.7) (thickness 0.15)) (justify right bottom))
    )
    (fp_rect (start -0.94 -0.47) (end 0.94 0.47)
      (stroke (width 0.05) (type solid)) (fill none) (layer "F.CrtYd"))
    (fp_rect (start -0.499 -0.249) (end 0.499 0.249)
      (stroke (width 0.15) (type solid)) (fill none) (layer "F.Fab"))
    (pad "1" smd roundrect (at -0.484 0 180) (size 0.59 0.64) (layers "F.Cu" "F.Paste" "F.Mask") (roundrect_rratio 0.25)
      (net 29 "Net-(U3-SDO-)") (pintype "passive"))
    (pad "2" smd roundrect (at 0.484 0 180) (size 0.59 0.64) (layers "F.Cu" "F.Paste" "F.Mask") (roundrect_rratio 0.25)
      (net 68 "Net-(C27-Pad2)") (pintype "passive"))
  )
	(footprint "sdi-mipi-bridge-footprints:C_0402_1005Metric" (layer "F.Cu")
    (at 113.76 116.4)
    (descr "Capacitor SMD 0402")
    (tags "capacitor SMD 0402")
    (property "Author" "Antmicro")
    (property "Dielectric" "")
    (property "License" "Apache-2.0")
    (property "MPN" "C1005X5R1E474M050BB")
    (property "Manufacturer" "TDK")
    (property "Sheetfile" "sdi-mipi-bridge.kicad_sch")
    (property "Sheetname" "")
    (property "Val" "470n")
    (property "Voltage" "")
    (property "ki_description" " ")
    (attr smd)
    (fp_text reference "C64" (at -7.16 -0.9) (layer "F.SilkS")
        (effects (font (size 0.65 0.65) (thickness 0.15)) (justify left bottom))
    )
    (fp_text value "C_470n_0402" (at 0 1.4) (layer "F.Fab") hide
        (effects (font (size 0.7 0.7) (thickness 0.15)) (justify left bottom))
    )
    (fp_text user "${REFERENCE}" (at -0.932 3.168) (layer "F.Fab") hide
        (effects (font (size 0.7 0.7) (thickness 0.15)) (justify left bottom))
    )
    (fp_text user "Author: Antmicro" (at -0.932 4.17) (layer "F.Fab") hide
        (effects (font (size 0.7 0.7) (thickness 0.15)) (justify left bottom))
    )
    (fp_text user "License: Apache-2.0" (at -0.932 5.17) (layer "F.Fab") hide
        (effects (font (size 0.7 0.7) (thickness 0.15)) (justify left bottom))
    )
    (fp_rect (start -0.94 -0.47) (end 0.94 0.47)
      (stroke (width 0.05) (type solid)) (fill none) (layer "F.CrtYd"))
    (fp_rect (start -0.499 -0.249) (end 0.499 0.249)
      (stroke (width 0.15) (type solid)) (fill none) (layer "F.Fab"))
    (pad "1" smd roundrect (at -0.484 0) (size 0.59 0.64) (layers "F.Cu" "F.Paste" "F.Mask") (roundrect_rratio 0.25)
      (net 12 "/AGCN") (pintype "passive"))
    (pad "2" smd roundrect (at 0.484 0) (size 0.59 0.64) (layers "F.Cu" "F.Paste" "F.Mask") (roundrect_rratio 0.25)
      (net 9 "/AGCP") (pintype "passive"))
  )
	(footprint "sdi-mipi-bridge-footprints:C_0402_1005Metric" (layer "F.Cu")
    (at 113.76 117.4)
    (descr "Capacitor SMD 0402")
    (tags "capacitor SMD 0402")
    (property "Author" "Antmicro")
    (property "Dielectric" "")
    (property "License" "Apache-2.0")
    (property "MPN" "C1005X5R1E474M050BB")
    (property "Manufacturer" "TDK")
    (property "Sheetfile" "sdi-mipi-bridge.kicad_sch")
    (property "Sheetname" "")
    (property "Val" "470n")
    (property "Voltage" "")
    (property "ki_description" " ")
    (attr smd)
    (fp_text reference "C61" (at -7.16 -0.9) (layer "F.SilkS")
        (effects (font (size 0.65 0.65) (thickness 0.15)) (justify left bottom))
    )
    (fp_text value "C_470n_0402" (at 0 1.4) (layer "F.Fab") hide
        (effects (font (size 0.7 0.7) (thickness 0.15)) (justify left bottom))
    )
    (fp_text user "License: Apache-2.0" (at -0.932 5.17) (layer "F.Fab") hide
        (effects (font (size 0.7 0.7) (thickness 0.15)) (justify left bottom))
    )
    (fp_text user "${REFERENCE}" (at -0.932 3.168) (layer "F.Fab") hide
        (effects (font (size 0.7 0.7) (thickness 0.15)) (justify left bottom))
    )
    (fp_text user "Author: Antmicro" (at -0.932 4.17) (layer "F.Fab") hide
        (effects (font (size 0.7 0.7) (thickness 0.15)) (justify left bottom))
    )
    (fp_rect (start -0.94 -0.47) (end 0.94 0.47)
      (stroke (width 0.05) (type solid)) (fill none) (layer "F.CrtYd"))
    (fp_rect (start -0.499 -0.249) (end 0.499 0.249)
      (stroke (width 0.15) (type solid)) (fill none) (layer "F.Fab"))
    (pad "1" smd roundrect (at -0.484 0) (size 0.59 0.64) (layers "F.Cu" "F.Paste" "F.Mask") (roundrect_rratio 0.25)
      (net 12 "/AGCN") (pintype "passive"))
    (pad "2" smd roundrect (at 0.484 0) (size 0.59 0.64) (layers "F.Cu" "F.Paste" "F.Mask") (roundrect_rratio 0.25)
      (net 3 "GNDA") (pintype "passive"))
  )
	(footprint "sdi-mipi-bridge-footprints:R_0603_1608Metric" (layer "F.Cu")
    (at 106.25 121.07 180)
    (descr "Resistor SMD 0603")
    (tags "resistor SMD 0603")
    (property "Author" "Antmicro")
    (property "License" "Apache-2.0")
    (property "MPN" "CR0603-FX-75R0ELF")
    (property "Manufacturer" "Bourns")
    (property "Sheetfile" "sdi-mipi-bridge.kicad_sch")
    (property "Sheetname" "")
    (property "Tolerance" "1%")
    (property "Val" "75R")
    (property "ki_description" "75R resistor in 0603 package with 1% tolerance")
    (attr smd)
    (fp_text reference "R17" (at -2.15 -9.43) (layer "F.SilkS")
        (effects (font (size 0.65 0.65) (thickness 0.15)) (justify right bottom))
    )
    (fp_text value "R_75R_0603" (at 0 1.6) (layer "F.Fab") hide
        (effects (font (size 0.7 0.7) (thickness 0.15)) (justify right bottom))
    )
    (fp_text user "License: Apache-2.0" (at -1.25 5.9) (layer "F.Fab") hide
        (effects (font (size 0.7 0.7) (thickness 0.15)) (justify right bottom))
    )
    (fp_text user "Author: Antmicro" (at -1.25 4.9) (layer "F.Fab") hide
        (effects (font (size 0.7 0.7) (thickness 0.15)) (justify right bottom))
    )
    (fp_text user "${REFERENCE}" (at -1.25 3.898) (layer "F.Fab") hide
        (effects (font (size 0.7 0.7) (thickness 0.15)) (justify right bottom))
    )
    (fp_line (start -0.3 -0.3) (end 0.3 -0.3)
      (stroke (width 0.15) (type solid)) (layer "F.SilkS"))
    (fp_line (start -0.3 0.3) (end 0.3 0.3)
      (stroke (width 0.15) (type solid)) (layer "F.SilkS"))
    (fp_rect (start -1.25 -0.7) (end 1.25 0.7)
      (stroke (width 0.05) (type solid)) (fill none) (layer "F.CrtYd"))
    (fp_rect (start -0.8 -0.4) (end 0.8 0.4)
      (stroke (width 0.15) (type solid)) (fill none) (layer "F.Fab"))
    (pad "1" smd roundrect (at -0.7 0 180) (size 0.6 0.8) (layers "F.Cu" "F.Paste" "F.Mask") (roundrect_rratio 0.2)
      (net 29 "Net-(U3-SDO-)") (pintype "passive"))
    (pad "2" smd roundrect (at 0.7 0 180) (size 0.6 0.8) (layers "F.Cu" "F.Paste" "F.Mask") (roundrect_rratio 0.2)
      (net 68 "Net-(C27-Pad2)") (pintype "passive"))
  )
	(footprint "sdi-mipi-bridge-footprints:R_0603_1608Metric" (layer "F.Cu")
    (at 108.35 120.340001 90)
    (descr "Resistor SMD 0603")
    (tags "resistor SMD 0603")
    (property "Author" "Antmicro")
    (property "License" "Apache-2.0")
    (property "MPN" "CR0603-FX-75R0ELF")
    (property "Manufacturer" "Bourns")
    (property "Sheetfile" "sdi-mipi-bridge.kicad_sch")
    (property "Sheetname" "")
    (property "Tolerance" "1%")
    (property "Val" "75R")
    (property "ki_description" "75R resistor in 0603 package with 1% tolerance")
    (attr smd)
    (fp_text reference "R19" (at -9.959999 1.45 90) (layer "F.SilkS")
        (effects (font (size 0.65 0.65) (thickness 0.15)) (justify left bottom))
    )
    (fp_text value "R_75R_0603" (at 0 1.6 90) (layer "F.Fab") hide
        (effects (font (size 0.7 0.7) (thickness 0.15)) (justify left bottom))
    )
    (fp_text user "License: Apache-2.0" (at -1.25 5.9 90) (layer "F.Fab") hide
        (effects (font (size 0.7 0.7) (thickness 0.15)) (justify left bottom))
    )
    (fp_text user "Author: Antmicro" (at -1.25 4.9 90) (layer "F.Fab") hide
        (effects (font (size 0.7 0.7) (thickness 0.15)) (justify left bottom))
    )
    (fp_text user "${REFERENCE}" (at -1.25 3.898 90) (layer "F.Fab") hide
        (effects (font (size 0.7 0.7) (thickness 0.15)) (justify left bottom))
    )
    (fp_line (start -0.3 -0.3) (end 0.3 -0.3)
      (stroke (width 0.15) (type solid)) (layer "F.SilkS"))
    (fp_line (start -0.3 0.3) (end 0.3 0.3)
      (stroke (width 0.15) (type solid)) (layer "F.SilkS"))
    (fp_rect (start -1.25 -0.7) (end 1.25 0.7)
      (stroke (width 0.05) (type solid)) (fill none) (layer "F.CrtYd"))
    (fp_rect (start -0.8 -0.4) (end 0.8 0.4)
      (stroke (width 0.15) (type solid)) (fill none) (layer "F.Fab"))
    (pad "1" smd roundrect (at -0.7 0 90) (size 0.6 0.8) (layers "F.Cu" "F.Paste" "F.Mask") (roundrect_rratio 0.2)
      (net 29 "Net-(U3-SDO-)") (pintype "passive"))
    (pad "2" smd roundrect (at 0.7 0 90) (size 0.6 0.8) (layers "F.Cu" "F.Paste" "F.Mask") (roundrect_rratio 0.2)
      (net 57 "VDD") (pintype "passive"))
  )
	(footprint "sdi-mipi-bridge-footprints:C_0402_1005Metric" (layer "F.Cu")
    (at 114.302 125.277)
    (descr "Capacitor SMD 0402")
    (tags "capacitor SMD 0402")
    (property "Author" "Antmicro")
    (property "Dielectric" "X7R")
    (property "License" "Apache-2.0")
    (property "MPN" "GRM155R71H103KA88D")
    (property "Manufacturer" "Murata")
    (property "Sheetfile" "sdi-mipi-bridge.kicad_sch")
    (property "Sheetname" "")
    (property "Val" "10n")
    (property "Voltage" "50V")
    (property "ki_description" " ")
    (attr smd)
    (fp_text reference "C18" (at -1.002 2.223) (layer "F.SilkS")
        (effects (font (size 0.65 0.65) (thickness 0.15)) (justify left bottom))
    )
    (fp_text value "C_10n_0402" (at 0 1.4) (layer "F.Fab") hide
        (effects (font (size 0.7 0.7) (thickness 0.15)) (justify left bottom))
    )
    (fp_text user "Author: Antmicro" (at -0.932 4.17) (layer "F.Fab") hide
        (effects (font (size 0.7 0.7) (thickness 0.15)) (justify left bottom))
    )
    (fp_text user "${REFERENCE}" (at -0.932 3.168) (layer "F.Fab") hide
        (effects (font (size 0.7 0.7) (thickness 0.15)) (justify left bottom))
    )
    (fp_text user "License: Apache-2.0" (at -0.932 5.17) (layer "F.Fab") hide
        (effects (font (size 0.7 0.7) (thickness 0.15)) (justify left bottom))
    )
    (fp_rect (start -0.94 -0.47) (end 0.94 0.47)
      (stroke (width 0.05) (type solid)) (fill none) (layer "F.CrtYd"))
    (fp_rect (start -0.499 -0.249) (end 0.499 0.249)
      (stroke (width 0.15) (type solid)) (fill none) (layer "F.Fab"))
    (pad "1" smd roundrect (at -0.484 0) (size 0.59 0.64) (layers "F.Cu" "F.Paste" "F.Mask") (roundrect_rratio 0.25)
      (net 3 "GNDA") (pintype "passive"))
    (pad "2" smd roundrect (at 0.484 0) (size 0.59 0.64) (layers "F.Cu" "F.Paste" "F.Mask") (roundrect_rratio 0.25)
      (net 57 "VDD") (pintype "passive"))
  )
)
